(kicad_pcb
	(version 20241229)
	(generator "pcbnew")
	(generator_version "9.0")
	(general
		(thickness 1.6296)
		(legacy_teardrops no)
	)
	(paper "A3")
	(title_block
		(title "Thunderbolt to 10GbE adapter")
		(date "2026-04-21")
		(rev "1.1.0")
		(company "Antmicro Ltd")
		(comment 1 "www.antmicro.com")
		(comment 9 "footprints 588-592 of 703")
	)
	(layers
		(0 "F.Cu" signal)
		(4 "In1.Cu" signal)
		(6 "In2.Cu" signal)
		(8 "In3.Cu" signal)
		(10 "In4.Cu" signal)
		(12 "In5.Cu" signal)
		(14 "In6.Cu" signal)
		(2 "B.Cu" signal)
		(9 "F.Adhes" user "F.Adhesive")
		(11 "B.Adhes" user "B.Adhesive")
		(13 "F.Paste" user)
		(15 "B.Paste" user)
		(5 "F.SilkS" user "F.Silkscreen")
		(7 "B.SilkS" user "B.Silkscreen")
		(1 "F.Mask" user)
		(3 "B.Mask" user)
		(17 "Dwgs.User" user "User.Drawings")
		(19 "Cmts.User" user "User.Comments")
		(21 "Eco1.User" user "User.Eco1")
		(23 "Eco2.User" user "User.Eco2")
		(25 "Edge.Cuts" user)
		(27 "Margin" user)
		(31 "F.CrtYd" user "F.Courtyard")
		(29 "B.CrtYd" user "B.Courtyard")
		(35 "F.Fab" user)
		(33 "B.Fab" user)
	)
	(footprint "antmicro-footprints:C_0402_1005Metric"
		(layer "B.Cu")
		(at 151.181866 79.260117 180)
		(descr "Capacitor SMD 0402")
		(tags "capacitor SMD 0402")
		(property "Reference" "C241"
			(at -20.368136 -9.464883 0)
			(layer "B.SilkS")
			(effects
				(font
					(size 0.7 0.7)
					(thickness 0.15)
				)
				(justify mirror)
			)
		)
		(property "Value" "C_1u_25V_0402"
			(at -1.022927 -2.155213 0)
			(layer "B.Fab")
			(effects
				(font
					(size 0.7 0.7)
					(thickness 0.15)
				)
				(justify left bottom mirror)
			)
		)
		(property "Datasheet" "https://www.murata.com/products/productdetail?partno=GRM155R61E105KE11%23"
			(at 0 0 0)
			(layer "B.Fab")
			(hide yes)
			(effects
				(font
					(size 1.27 1.27)
					(thickness 0.15)
				)
				(justify mirror)
			)
		)
		(property "Description" "SMD Multilayer Ceramic Capacitor, 1 µF, 25 V, 0402 [1005 Metric], ± 10%, X5R, GRM Series"
			(at 0 0 0)
			(layer "B.Fab")
			(hide yes)
			(effects
				(font
					(size 1.27 1.27)
					(thickness 0.15)
				)
				(justify mirror)
			)
		)
		(property "MPN" "GRM155R61E105KE11J"
			(at 0 0 180)
			(unlocked yes)
			(layer "B.Fab")
			(hide yes)
			(effects
				(font
					(size 1 1)
					(thickness 0.15)
				)
				(justify mirror)
			)
		)
		(property "Manufacturer" "Murata"
			(at 0 0 180)
			(unlocked yes)
			(layer "B.Fab")
			(hide yes)
			(effects
				(font
					(size 1 1)
					(thickness 0.15)
				)
				(justify mirror)
			)
		)
		(property "License" "Apache-2.0"
			(at 0 0 180)
			(unlocked yes)
			(layer "B.Fab")
			(hide yes)
			(effects
				(font
					(size 1 1)
					(thickness 0.15)
				)
				(justify mirror)
			)
		)
		(property "Author" "Antmicro"
			(at 0 0 180)
			(unlocked yes)
			(layer "B.Fab")
			(hide yes)
			(effects
				(font
					(size 1 1)
					(thickness 0.15)
				)
				(justify mirror)
			)
		)
		(property "Val" "1u"
			(at 0 0 180)
			(unlocked yes)
			(layer "B.Fab")
			(hide yes)
			(effects
				(font
					(size 1 1)
					(thickness 0.15)
				)
				(justify mirror)
			)
		)
		(property "Voltage" "25V"
			(at 0 0 180)
			(unlocked yes)
			(layer "B.Fab")
			(hide yes)
			(effects
				(font
					(size 1 1)
					(thickness 0.15)
				)
				(justify mirror)
			)
		)
		(property "Dielectric" "X5R"
			(at 0 0 180)
			(unlocked yes)
			(layer "B.Fab")
			(hide yes)
			(effects
				(font
					(size 1 1)
					(thickness 0.15)
				)
				(justify mirror)
			)
		)
		(sheetname "/X710-AT2 power/")
		(sheetfile "x710-at2-power.kicad_sch")
		(attr smd)
		(fp_rect
			(start -0.925 0.47)
			(end 0.925 -0.47)
			(stroke
				(width 0.05)
				(type default)
			)
			(fill no)
			(layer "B.CrtYd")
		)
		(fp_line
			(start 0.504 0.25)
			(end 0.504 -0.248)
			(stroke
				(width 0.15)
				(type solid)
			)
			(layer "B.Fab")
		)
		(fp_line
			(start 0.504 -0.248)
			(end -0.494 -0.248)
			(stroke
				(width 0.15)
				(type solid)
			)
			(layer "B.Fab")
		)
		(fp_line
			(start -0.494 0.25)
			(end 0.504 0.25)
			(stroke
				(width 0.15)
				(type solid)
			)
			(layer "B.Fab")
		)
		(fp_line
			(start -0.494 -0.248)
			(end -0.494 0.25)
			(stroke
				(width 0.15)
				(type solid)
			)
			(layer "B.Fab")
		)
		(fp_text user "Author: Antmicro"
			(at -0.939 -3.399 0)
			(layer "B.Fab")
			(effects
				(font
					(size 0.7 0.7)
					(thickness 0.15)
				)
				(justify left bottom mirror)
			)
		)
		(fp_text user "${REFERENCE}"
			(at -0.939 -4.599 0)
			(layer "B.Fab")
			(effects
				(font
					(size 0.7 0.7)
					(thickness 0.15)
				)
				(justify left bottom mirror)
			)
		)
		(fp_text user "License: Apache-2.0"
			(at -0.939 -5.799 0)
			(layer "B.Fab")
			(effects
				(font
					(size 0.7 0.7)
					(thickness 0.15)
				)
				(justify left bottom mirror)
			)
		)
		(pad "1" smd roundrect
			(at -0.48 0 180)
			(size 0.59 0.64)
			(layers "B.Cu" "B.Mask" "B.Paste")
			(roundrect_rratio 0.25)
			(net 23 "GND")
			(pintype "passive")
		)
		(pad "2" smd roundrect
			(at 0.48 0 180)
			(size 0.59 0.64)
			(layers "B.Cu" "B.Mask" "B.Paste")
			(roundrect_rratio 0.25)
			(net 9 "VCCD")
			(pintype "passive")
		)
	)
	(footprint "antmicro-footprints:C_0402_1005Metric"
		(layer "B.Cu")
		(at 127.999999 125.425001 180)
		(descr "Capacitor SMD 0402")
		(tags "capacitor SMD 0402")
		(property "Reference" "C62"
			(at -21.900002 7.700002 0)
			(layer "B.SilkS")
			(effects
				(font
					(size 0.7 0.7)
					(thickness 0.15)
				)
				(justify mirror)
			)
		)
		(property "Value" "C_1u_0402"
			(at -1.022927 -2.155213 0)
			(layer "B.Fab")
			(effects
				(font
					(size 0.7 0.7)
					(thickness 0.15)
				)
				(justify left bottom mirror)
			)
		)
		(property "Datasheet" "https://product.tdk.com/en/search/capacitor/ceramic/mlcc/info?part_no=C1005X6S1A105K050BC"
			(at 0 0 0)
			(layer "B.Fab")
			(hide yes)
			(effects
				(font
					(size 1.27 1.27)
					(thickness 0.15)
				)
				(justify mirror)
			)
		)
		(property "Description" "SMD Multilayer Ceramic Capacitor, 1 µF, 10 V, 0402 [1005 Metric], ± 10%, X6S, C"
			(at 0 0 0)
			(layer "B.Fab")
			(hide yes)
			(effects
				(font
					(size 1.27 1.27)
					(thickness 0.15)
				)
				(justify mirror)
			)
		)
		(property "MPN" "C1005X6S1A105K050BC"
			(at 0 0 180)
			(unlocked yes)
			(layer "B.Fab")
			(hide yes)
			(effects
				(font
					(size 1 1)
					(thickness 0.15)
				)
				(justify mirror)
			)
		)
		(property "Manufacturer" "TDK"
			(at 0 0 180)
			(unlocked yes)
			(layer "B.Fab")
			(hide yes)
			(effects
				(font
					(size 1 1)
					(thickness 0.15)
				)
				(justify mirror)
			)
		)
		(property "License" "Apache-2.0"
			(at 0 0 180)
			(unlocked yes)
			(layer "B.Fab")
			(hide yes)
			(effects
				(font
					(size 1 1)
					(thickness 0.15)
				)
				(justify mirror)
			)
		)
		(property "Val" "1u"
			(at 0 0 180)
			(unlocked yes)
			(layer "B.Fab")
			(hide yes)
			(effects
				(font
					(size 1 1)
					(thickness 0.15)
				)
				(justify mirror)
			)
		)
		(property "Voltage" ""
			(at 0 0 180)
			(unlocked yes)
			(layer "B.Fab")
			(hide yes)
			(effects
				(font
					(size 1 1)
					(thickness 0.15)
				)
				(justify mirror)
			)
		)
		(property "Dielectric" ""
			(at 0 0 180)
			(unlocked yes)
			(layer "B.Fab")
			(hide yes)
			(effects
				(font
					(size 1 1)
					(thickness 0.15)
				)
				(justify mirror)
			)
		)
		(property "Author" "Antmicro"
			(at 0 0 180)
			(unlocked yes)
			(layer "B.Fab")
			(hide yes)
			(effects
				(font
					(size 1 1)
					(thickness 0.15)
				)
				(justify mirror)
			)
		)
		(sheetname "/TB Controller - Power/")
		(sheetfile "tb-power.kicad_sch")
		(attr smd)
		(fp_rect
			(start -0.925 0.47)
			(end 0.925 -0.47)
			(stroke
				(width 0.05)
				(type default)
			)
			(fill no)
			(layer "B.CrtYd")
		)
		(fp_line
			(start 0.504 0.25)
			(end 0.504 -0.248)
			(stroke
				(width 0.15)
				(type solid)
			)
			(layer "B.Fab")
		)
		(fp_line
			(start 0.504 -0.248)
			(end -0.494 -0.248)
			(stroke
				(width 0.15)
				(type solid)
			)
			(layer "B.Fab")
		)
		(fp_line
			(start -0.494 0.25)
			(end 0.504 0.25)
			(stroke
				(width 0.15)
				(type solid)
			)
			(layer "B.Fab")
		)
		(fp_line
			(start -0.494 -0.248)
			(end -0.494 0.25)
			(stroke
				(width 0.15)
				(type solid)
			)
			(layer "B.Fab")
		)
		(fp_text user "${REFERENCE}"
			(at -0.939 -4.599 0)
			(layer "B.Fab")
			(effects
				(font
					(size 0.7 0.7)
					(thickness 0.15)
				)
				(justify left bottom mirror)
			)
		)
		(fp_text user "License: Apache-2.0"
			(at -0.939 -5.799 0)
			(layer "B.Fab")
			(effects
				(font
					(size 0.7 0.7)
					(thickness 0.15)
				)
				(justify left bottom mirror)
			)
		)
		(fp_text user "Author: Antmicro"
			(at -0.939 -3.399 0)
			(layer "B.Fab")
			(effects
				(font
					(size 0.7 0.7)
					(thickness 0.15)
				)
				(justify left bottom mirror)
			)
		)
		(pad "1" smd roundrect
			(at -0.48 0 180)
			(size 0.59 0.64)
			(layers "B.Cu" "B.Mask" "B.Paste")
			(roundrect_rratio 0.25)
			(net 23 "GND")
			(pintype "passive")
		)
		(pad "2" smd roundrect
			(at 0.48 0 180)
			(size 0.59 0.64)
			(layers "B.Cu" "B.Mask" "B.Paste")
			(roundrect_rratio 0.25)
			(net 177 "Net-(U4A-VCC3P3_ANA_PCIE)")
			(pintype "passive")
		)
	)
	(footprint "antmicro-footprints:C_0402_1005Metric"
		(layer "B.Cu")
		(at 151.181867 81.260117 180)
		(descr "Capacitor SMD 0402")
		(tags "capacitor SMD 0402")
		(property "Reference" "C224"
			(at -20.368136 -9.464883 0)
			(layer "B.SilkS")
			(effects
				(font
					(size 0.7 0.7)
					(thickness 0.15)
				)
				(justify mirror)
			)
		)
		(property "Value" "C_1u_25V_0402"
			(at -1.022927 -2.155213 0)
			(layer "B.Fab")
			(effects
				(font
					(size 0.7 0.7)
					(thickness 0.15)
				)
				(justify left bottom mirror)
			)
		)
		(property "Datasheet" "https://www.murata.com/products/productdetail?partno=GRM155R61E105KE11%23"
			(at 0 0 0)
			(layer "B.Fab")
			(hide yes)
			(effects
				(font
					(size 1.27 1.27)
					(thickness 0.15)
				)
				(justify mirror)
			)
		)
		(property "Description" "SMD Multilayer Ceramic Capacitor, 1 µF, 25 V, 0402 [1005 Metric], ± 10%, X5R, GRM Series"
			(at 0 0 0)
			(layer "B.Fab")
			(hide yes)
			(effects
				(font
					(size 1.27 1.27)
					(thickness 0.15)
				)
				(justify mirror)
			)
		)
		(property "MPN" "GRM155R61E105KE11J"
			(at 0 0 180)
			(unlocked yes)
			(layer "B.Fab")
			(hide yes)
			(effects
				(font
					(size 1 1)
					(thickness 0.15)
				)
				(justify mirror)
			)
		)
		(property "Manufacturer" "Murata"
			(at 0 0 180)
			(unlocked yes)
			(layer "B.Fab")
			(hide yes)
			(effects
				(font
					(size 1 1)
					(thickness 0.15)
				)
				(justify mirror)
			)
		)
		(property "License" "Apache-2.0"
			(at 0 0 180)
			(unlocked yes)
			(layer "B.Fab")
			(hide yes)
			(effects
				(font
					(size 1 1)
					(thickness 0.15)
				)
				(justify mirror)
			)
		)
		(property "Author" "Antmicro"
			(at 0 0 180)
			(unlocked yes)
			(layer "B.Fab")
			(hide yes)
			(effects
				(font
					(size 1 1)
					(thickness 0.15)
				)
				(justify mirror)
			)
		)
		(property "Val" "1u"
			(at 0 0 180)
			(unlocked yes)
			(layer "B.Fab")
			(hide yes)
			(effects
				(font
					(size 1 1)
					(thickness 0.15)
				)
				(justify mirror)
			)
		)
		(property "Voltage" "25V"
			(at 0 0 180)
			(unlocked yes)
			(layer "B.Fab")
			(hide yes)
			(effects
				(font
					(size 1 1)
					(thickness 0.15)
				)
				(justify mirror)
			)
		)
		(property "Dielectric" "X5R"
			(at 0 0 180)
			(unlocked yes)
			(layer "B.Fab")
			(hide yes)
			(effects
				(font
					(size 1 1)
					(thickness 0.15)
				)
				(justify mirror)
			)
		)
		(sheetname "/X710-AT2 power/")
		(sheetfile "x710-at2-power.kicad_sch")
		(attr smd)
		(fp_rect
			(start -0.925 0.47)
			(end 0.925 -0.47)
			(stroke
				(width 0.05)
				(type default)
			)
			(fill no)
			(layer "B.CrtYd")
		)
		(fp_line
			(start 0.504 0.25)
			(end 0.504 -0.248)
			(stroke
				(width 0.15)
				(type solid)
			)
			(layer "B.Fab")
		)
		(fp_line
			(start 0.504 -0.248)
			(end -0.494 -0.248)
			(stroke
				(width 0.15)
				(type solid)
			)
			(layer "B.Fab")
		)
		(fp_line
			(start -0.494 0.25)
			(end 0.504 0.25)
			(stroke
				(width 0.15)
				(type solid)
			)
			(layer "B.Fab")
		)
		(fp_line
			(start -0.494 -0.248)
			(end -0.494 0.25)
			(stroke
				(width 0.15)
				(type solid)
			)
			(layer "B.Fab")
		)
		(fp_text user "Author: Antmicro"
			(at -0.939 -3.399 0)
			(layer "B.Fab")
			(effects
				(font
					(size 0.7 0.7)
					(thickness 0.15)
				)
				(justify left bottom mirror)
			)
		)
		(fp_text user "${REFERENCE}"
			(at -0.939 -4.599 0)
			(layer "B.Fab")
			(effects
				(font
					(size 0.7 0.7)
					(thickness 0.15)
				)
				(justify left bottom mirror)
			)
		)
		(fp_text user "License: Apache-2.0"
			(at -0.939 -5.799 0)
			(layer "B.Fab")
			(effects
				(font
					(size 0.7 0.7)
					(thickness 0.15)
				)
				(justify left bottom mirror)
			)
		)
		(pad "1" smd roundrect
			(at -0.48 0 180)
			(size 0.59 0.64)
			(layers "B.Cu" "B.Mask" "B.Paste")
			(roundrect_rratio 0.25)
			(net 23 "GND")
			(pintype "passive")
		)
		(pad "2" smd roundrect
			(at 0.48 0 180)
			(size 0.59 0.64)
			(layers "B.Cu" "B.Mask" "B.Paste")
			(roundrect_rratio 0.25)
			(net 9 "VCCD")
			(pintype "passive")
		)
	)
	(footprint "antmicro-footprints:R_0402_1005Metric"
		(layer "B.Cu")
		(at 158.131866 70.035118 -90)
		(descr "Resistor SMD 0402")
		(tags "resistor SMD 0402")
		(property "Reference" "R166"
			(at 9.464883 -19.468134 90)
			(layer "B.SilkS")
			(effects
				(font
					(size 0.7 0.7)
					(thickness 0.15)
				)
				(justify mirror)
			)
		)
		(property "Value" "R_22R_0402"
			(at -1.011843 -1.772047 90)
			(layer "B.Fab")
			(effects
				(font
					(size 0.7 0.7)
					(thickness 0.15)
				)
				(justify left bottom mirror)
			)
		)
		(property "Datasheet" "https://www.bourns.com/docs/product-datasheets/cr.pdf"
			(at 0 0 90)
			(layer "B.Fab")
			(hide yes)
			(effects
				(font
					(size 1.27 1.27)
					(thickness 0.15)
				)
				(justify mirror)
			)
		)
		(property "Description" "SMD Chip Resistor, 22 ohm, ± 1%, 62.5 mW, 0402 [1005 Metric], Thick Film, General Purpose"
			(at 0 0 90)
			(layer "B.Fab")
			(hide yes)
			(effects
				(font
					(size 1.27 1.27)
					(thickness 0.15)
				)
				(justify mirror)
			)
		)
		(property "MPN" "CR0402-FX-22R0GLF"
			(at 0 0 270)
			(unlocked yes)
			(layer "B.Fab")
			(hide yes)
			(effects
				(font
					(size 1 1)
					(thickness 0.15)
				)
				(justify mirror)
			)
		)
		(property "Manufacturer" "Bourns"
			(at 0 0 270)
			(unlocked yes)
			(layer "B.Fab")
			(hide yes)
			(effects
				(font
					(size 1 1)
					(thickness 0.15)
				)
				(justify mirror)
			)
		)
		(property "License" "Apache-2.0"
			(at 0 0 270)
			(unlocked yes)
			(layer "B.Fab")
			(hide yes)
			(effects
				(font
					(size 1 1)
					(thickness 0.15)
				)
				(justify mirror)
			)
		)
		(property "Author" "Antmicro"
			(at 0 0 270)
			(unlocked yes)
			(layer "B.Fab")
			(hide yes)
			(effects
				(font
					(size 1 1)
					(thickness 0.15)
				)
				(justify mirror)
			)
		)
		(property "Val" "22R"
			(at 0 0 270)
			(unlocked yes)
			(layer "B.Fab")
			(hide yes)
			(effects
				(font
					(size 1 1)
					(thickness 0.15)
				)
				(justify mirror)
			)
		)
		(property "Tolerance" "1%"
			(at 0 0 270)
			(unlocked yes)
			(layer "B.Fab")
			(hide yes)
			(effects
				(font
					(size 1 1)
					(thickness 0.15)
				)
				(justify mirror)
			)
		)
		(sheetname "/X710-AT2 Misc/")
		(sheetfile "x710-at2-mics.kicad_sch")
		(attr smd)
		(fp_rect
			(start -0.925 0.47)
			(end 0.925 -0.47)
			(stroke
				(width 0.05)
				(type default)
			)
			(fill no)
			(layer "B.CrtYd")
		)
		(fp_rect
			(start -0.5 0.25)
			(end 0.5 -0.25)
			(stroke
				(width 0.15)
				(type solid)
			)
			(fill no)
			(layer "B.Fab")
		)
		(fp_text user "License: Apache-2.0"
			(at -0.95 -5.169 90)
			(layer "B.Fab")
			(effects
				(font
					(size 0.7 0.7)
					(thickness 0.15)
				)
				(justify left bottom mirror)
			)
		)
		(fp_text user "Author: Antmicro"
			(at -0.95 -4.169 90)
			(layer "B.Fab")
			(effects
				(font
					(size 0.7 0.7)
					(thickness 0.15)
				)
				(justify left bottom mirror)
			)
		)
		(fp_text user "${REFERENCE}"
			(at -0.95 -3.168 90)
			(layer "B.Fab")
			(effects
				(font
					(size 0.7 0.7)
					(thickness 0.15)
				)
				(justify left bottom mirror)
			)
		)
		(pad "1" smd roundrect
			(at -0.48 0 270)
			(size 0.59 0.64)
			(layers "B.Cu" "B.Mask" "B.Paste")
			(roundrect_rratio 0.25)
			(net 141 "/X710-AT2 Misc/NCSI.ARB_OUT")
			(pintype "passive")
		)
		(pad "2" smd roundrect
			(at 0.48 0 270)
			(size 0.59 0.64)
			(layers "B.Cu" "B.Mask" "B.Paste")
			(roundrect_rratio 0.25)
			(net 440 "Net-(U14D-NCSI_ARB_OUT)")
			(pintype "passive")
		)
	)
	(footprint "antmicro-footprints:R_0402_1005Metric"
		(layer "B.Cu")
		(at 157.511866 90.455117 90)
		(descr "Resistor SMD 0402")
		(tags "resistor SMD 0402")
		(property "Reference" "R209"
			(at -10.794883 19.288134 270)
			(layer "B.SilkS")
			(effects
				(font
					(size 0.7 0.7)
					(thickness 0.15)
				)
				(justify mirror)
			)
		)
		(property "Value" "R_6k04_0.1%_0402"
			(at -1.011843 -1.772047 270)
			(layer "B.Fab")
			(effects
				(font
					(size 0.7 0.7)
					(thickness 0.15)
				)
				(justify left bottom mirror)
			)
		)
		(property "Datasheet" "https://www.vishay.com/docs/28758/tnpw_e3.pdf"
			(at 0 0 270)
			(layer "B.Fab")
			(hide yes)
			(effects
				(font
					(size 1.27 1.27)
					(thickness 0.15)
				)
				(justify mirror)
			)
		)
		(property "Description" "SMD Chip Resistor, 6.49 kohm, ± 1%, 62.5 mW, 0402 [1005 Metric], Thick Film, General Purpose"
			(at 0 0 270)
			(layer "B.Fab")
			(hide yes)
			(effects
				(font
					(size 1.27 1.27)
					(thickness 0.15)
				)
				(justify mirror)
			)
		)
		(property "MPN" "TNPW04026K04BEED"
			(at 0 0 90)
			(unlocked yes)
			(layer "B.Fab")
			(hide yes)
			(effects
				(font
					(size 1 1)
					(thickness 0.15)
				)
				(justify mirror)
			)
		)
		(property "Manufacturer" "Vishay"
			(at 0 0 90)
			(unlocked yes)
			(layer "B.Fab")
			(hide yes)
			(effects
				(font
					(size 1 1)
					(thickness 0.15)
				)
				(justify mirror)
			)
		)
		(property "License" "Apache-2.0"
			(at 0 0 90)
			(unlocked yes)
			(layer "B.Fab")
			(hide yes)
			(effects
				(font
					(size 1 1)
					(thickness 0.15)
				)
				(justify mirror)
			)
		)
		(property "Author" "Antmicro"
			(at 0 0 90)
			(unlocked yes)
			(layer "B.Fab")
			(hide yes)
			(effects
				(font
					(size 1 1)
					(thickness 0.15)
				)
				(justify mirror)
			)
		)
		(property "Val" "6k04"
			(at 0 0 90)
			(unlocked yes)
			(layer "B.Fab")
			(hide yes)
			(effects
				(font
					(size 1 1)
					(thickness 0.15)
				)
				(justify mirror)
			)
		)
		(property "Tolerance" "0.1%"
			(at 0 0 90)
			(unlocked yes)
			(layer "B.Fab")
			(hide yes)
			(effects
				(font
					(size 1 1)
					(thickness 0.15)
				)
				(justify mirror)
			)
		)
		(sheetname "/X710-AT2 10GbE/")
		(sheetfile "x710-at2-10gbe.kicad_sch")
		(attr smd)
		(fp_rect
			(start -0.925 0.47)
			(end 0.925 -0.47)
			(stroke
				(width 0.05)
				(type default)
			)
			(fill no)
			(layer "B.CrtYd")
		)
		(fp_rect
			(start -0.5 0.25)
			(end 0.5 -0.25)
			(stroke
				(width 0.15)
				(type solid)
			)
			(fill no)
			(layer "B.Fab")
		)
		(fp_text user "Author: Antmicro"
			(at -0.95 -4.169 270)
			(layer "B.Fab")
			(effects
				(font
					(size 0.7 0.7)
					(thickness 0.15)
				)
				(justify left bottom mirror)
			)
		)
		(fp_text user "${REFERENCE}"
			(at -0.95 -3.168 270)
			(layer "B.Fab")
			(effects
				(font
					(size 0.7 0.7)
					(thickness 0.15)
				)
				(justify left bottom mirror)
			)
		)
		(fp_text user "License: Apache-2.0"
			(at -0.95 -5.169 270)
			(layer "B.Fab")
			(effects
				(font
					(size 0.7 0.7)
					(thickness 0.15)
				)
				(justify left bottom mirror)
			)
		)
		(pad "1" smd roundrect
			(at -0.48 0 90)
			(size 0.59 0.64)
			(layers "B.Cu" "B.Mask" "B.Paste")
			(roundrect_rratio 0.25)
			(net 23 "GND")
			(pintype "passive")
		)
		(pad "2" smd roundrect
			(at 0.48 0 90)
			(size 0.59 0.64)
			(layers "B.Cu" "B.Mask" "B.Paste")
			(roundrect_rratio 0.25)
			(net 63 "/X710-AT2 10GbE/BIAS_RDAC")
			(pintype "passive")
		)
	)
)
